(kicad_pcb
	(version 20260206)
	(generator "pcbnew")
	(generator_version "10.0")
	(general
		(thickness 1.6)
		(legacy_teardrops no)
	)
	(paper "A4")
	(title_block
		(title "04192023_DAF0TMB3IC0_F0TG_MB_C_brd_V02_OCP.brd")
		(comment 1 "Grand Teton / footprints 7936-7942 of 8354")
	)
	(layers
		(0 "F.Cu" signal "TOP")
		(4 "In1.Cu" signal "GND")
		(6 "In2.Cu" signal "IN1")
		(8 "In3.Cu" signal "GND1")
		(10 "In4.Cu" signal "IN2")
		(12 "In5.Cu" signal "GND2")
		(14 "In6.Cu" signal "IN3")
		(16 "In7.Cu" signal "GND3")
		(18 "In8.Cu" signal "VCC")
		(20 "In9.Cu" signal "VCC1")
		(22 "In10.Cu" signal "GND4")
		(24 "In11.Cu" signal "IN4")
		(26 "In12.Cu" signal "GND5")
		(28 "In13.Cu" signal "IN5")
		(30 "In14.Cu" signal "GND6")
		(32 "In15.Cu" signal "IN6")
		(34 "In16.Cu" signal "GND7")
		(2 "B.Cu" signal "BOTTOM")
		(9 "F.Adhes" user "F.Adhesive")
		(11 "B.Adhes" user "B.Adhesive")
		(13 "F.Paste" user "Package Geometry/Pastemask Top")
		(15 "B.Paste" user "Package Geometry/Pastemask Bottom")
		(5 "F.SilkS" user "Ref Des/Silkscreen Top")
		(7 "B.SilkS" user "Ref Des/Silkscreen Bottom")
		(1 "F.Mask" user "Board Geometry/Soldermask Top")
		(3 "B.Mask" user "Board Geometry/Soldermask Bottom")
		(17 "Dwgs.User" user "User.Drawings")
		(19 "Cmts.User" user "User.Comments")
		(21 "Eco1.User" user "User.Eco1")
		(23 "Eco2.User" user "User.Eco2")
		(25 "Edge.Cuts" user "Board Geometry/Outline")
		(27 "Margin" user)
		(31 "F.CrtYd" user "Package Geometry/Place Bound Top")
		(29 "B.CrtYd" user "Package Geometry/Place Bound Bottom")
		(35 "F.Fab" user "Ref Des/Assembly Top")
		(33 "B.Fab" user "Ref Des/Assembly Bottom")
	)
	(footprint ""
		(layer "B.Cu")
		(at 495.90833 -142.853918 -90)
		(property "Reference" "X8028"
			(at 4.4577 -1.50495 270)
			(unlocked yes)
			(layer "B.SilkS")
			(effects
				(font
					(size 0.7874 0.5842)
					(thickness 0.1524)
				)
				(justify left mirror)
			)
		)
		(property "Value" ""
			(at 0 0 90)
			(layer "B.Fab")
			(effects
				(font
					(size 1.27 1.27)
				)
				(justify mirror)
			)
		)
		(property "Device Type" "TP_TDR_4P_FTS_TH-TP_TDR_4P_DIP,EMPTY,TP15"
			(at -1.30175 1.27 180)
			(unlocked yes)
			(layer "B.Fab")
			(hide yes)
			(effects
				(font
					(size 0.635 0.4064)
					(thickness 0.1524)
				)
				(justify mirror)
			)
		)
		(property "User Part Number" "N_A"
			(at -1.30175 1.27 180)
			(unlocked yes)
			(layer "Cmts.User")
			(hide yes)
			(effects
				(font
					(size 0.635 0.4064)
					(thickness 0.1524)
				)
				(justify mirror)
			)
		)
		(duplicate_pad_numbers_are_jumpers no)
		(fp_line
			(start -2.54 3.81)
			(end -2.54 3.6703)
			(stroke
				(width 0.1524)
				(type default)
			)
			(layer "B.SilkS")
		)
		(fp_line
			(start 0 3.81)
			(end -2.54 3.81)
			(stroke
				(width 0.1524)
				(type default)
			)
			(layer "B.SilkS")
		)
		(fp_line
			(start 0 3.175)
			(end 0 3.81)
			(stroke
				(width 0.1524)
				(type default)
			)
			(layer "B.SilkS")
		)
		(fp_line
			(start -2.54 1.4097)
			(end -2.54 1.1303)
			(stroke
				(width 0.1524)
				(type default)
			)
			(layer "B.SilkS")
		)
		(fp_line
			(start 0 0.635)
			(end 0 1.905)
			(stroke
				(width 0.1524)
				(type default)
			)
			(layer "B.SilkS")
		)
		(fp_line
			(start -2.54 -1.1303)
			(end -2.54 -1.27)
			(stroke
				(width 0.1524)
				(type default)
			)
			(layer "B.SilkS")
		)
		(fp_line
			(start -2.54 -1.27)
			(end 0 -1.27)
			(stroke
				(width 0.1524)
				(type default)
			)
			(layer "B.SilkS")
		)
		(fp_line
			(start 0 -1.27)
			(end 0 -0.635)
			(stroke
				(width 0.1524)
				(type default)
			)
			(layer "B.SilkS")
		)
		(fp_poly
			(pts
				(xy 0.761746 0) (xy 2.285746 -0.762) (xy 2.285746 0.762)
			)
			(stroke
				(width 0)
				(type default)
			)
			(fill yes)
			(layer "B.SilkS")
		)
		(fp_line
			(start -2.54 3.81)
			(end -2.54 -1.27)
			(stroke
				(width 0.1)
				(type default)
			)
			(layer "B.Fab")
		)
		(fp_line
			(start 0 3.81)
			(end -2.54 3.81)
			(stroke
				(width 0.1)
				(type default)
			)
			(layer "B.Fab")
		)
		(fp_line
			(start -2.54 -1.27)
			(end 0 -1.27)
			(stroke
				(width 0.1)
				(type default)
			)
			(layer "B.Fab")
		)
		(fp_line
			(start 0 -1.27)
			(end 0 3.81)
			(stroke
				(width 0.1)
				(type default)
			)
			(layer "B.Fab")
		)
		(fp_poly
			(pts
				(xy 0.761746 0) (xy 2.285746 -0.762) (xy 2.285746 0.762)
			)
			(stroke
				(width 0)
				(type default)
			)
			(fill yes)
			(layer "B.Fab")
		)
		(pad "1" thru_hole circle
			(at 0 0 90)
			(size 1.0033 1.0033)
			(drill 0.249936)
			(layers "*.Cu" "*.Mask")
			(remove_unused_layers no)
			(net "TDR_DIFF_85_IN6_DN")
			(clearance 0.10795)
			(padstack
				(mode front_inner_back)
				(layer "Inner"
					(shape circle)
					(size 0.8001 0.8001)
					(clearance 0.1524)
				)
				(layer "B.Cu"
					(shape circle)
					(size 1.0033 1.0033)
					(thermal_gap 0.10795)
					(clearance 0.10795)
				)
			)
		)
		(pad "2" thru_hole circle
			(at -2.54 0 90)
			(size 1.9939 1.9939)
			(drill 0.249936)
			(layers "*.Cu" "*.Mask")
			(remove_unused_layers no)
			(net "T1_GND")
			(clearance 0.10795)
			(padstack
				(mode front_inner_back)
				(layer "Inner"
					(shape circle)
					(size 0.8001 0.8001)
					(clearance 0.1524)
				)
				(layer "B.Cu"
					(shape circle)
					(size 1.9939 1.9939)
					(thermal_gap 0.10795)
					(clearance 0.10795)
				)
			)
		)
		(pad "3" thru_hole circle
			(at -2.54 2.54 90)
			(size 1.9939 1.9939)
			(drill 0.249936)
			(layers "*.Cu" "*.Mask")
			(remove_unused_layers no)
			(net "T1_GND")
			(clearance 0.10795)
			(padstack
				(mode front_inner_back)
				(layer "Inner"
					(shape circle)
					(size 0.8001 0.8001)
					(clearance 0.1524)
				)
				(layer "B.Cu"
					(shape circle)
					(size 1.9939 1.9939)
					(thermal_gap 0.10795)
					(clearance 0.10795)
				)
			)
		)
		(pad "4" thru_hole circle
			(at 0 2.54 90)
			(size 1.0033 1.0033)
			(drill 0.249936)
			(layers "*.Cu" "*.Mask")
			(remove_unused_layers no)
			(net "TDR_DIFF_85_IN6_DP")
			(clearance 0.10795)
			(padstack
				(mode front_inner_back)
				(layer "Inner"
					(shape circle)
					(size 0.8001 0.8001)
					(clearance 0.1524)
				)
				(layer "B.Cu"
					(shape circle)
					(size 1.0033 1.0033)
					(thermal_gap 0.10795)
					(clearance 0.10795)
				)
			)
		)
	)
	(footprint ""
		(layer "B.Cu")
		(at 299.06849 -193.99631)
		(property "Reference" "C92"
			(at 0 0 0)
			(layer "B.SilkS")
			(hide yes)
			(effects
				(font
					(size 1.27 1.27)
				)
				(justify mirror)
			)
		)
		(property "Value" ""
			(at 0 0 0)
			(layer "B.Fab")
			(effects
				(font
					(size 1.27 1.27)
				)
				(justify mirror)
			)
		)
		(duplicate_pad_numbers_are_jumpers no)
		(fp_line
			(start -0.7874 -0.4064)
			(end -0.7874 0.4064)
			(stroke
				(width 0.1524)
				(type default)
			)
			(layer "B.SilkS")
		)
		(fp_line
			(start -0.7874 0.4064)
			(end 0.7874 0.4064)
			(stroke
				(width 0.1524)
				(type default)
			)
			(layer "B.SilkS")
		)
		(fp_line
			(start 0.7874 -0.4064)
			(end -0.7874 -0.4064)
			(stroke
				(width 0.1524)
				(type default)
			)
			(layer "B.SilkS")
		)
		(fp_line
			(start 0.7874 0.4064)
			(end 0.7874 -0.4064)
			(stroke
				(width 0.1524)
				(type default)
			)
			(layer "B.SilkS")
		)
		(fp_line
			(start -0.67945 -0.3048)
			(end -0.67945 0.3048)
			(stroke
				(width 0.1)
				(type default)
			)
			(layer "B.Fab")
		)
		(fp_line
			(start -0.67945 0.3048)
			(end -0.120396 0.3048)
			(stroke
				(width 0.1)
				(type default)
			)
			(layer "B.Fab")
		)
		(fp_line
			(start -0.12065 -0.3048)
			(end -0.67945 -0.3048)
			(stroke
				(width 0.1)
				(type default)
			)
			(layer "B.Fab")
		)
		(fp_line
			(start -0.12065 -0.2794)
			(end -0.12065 -0.3048)
			(stroke
				(width 0.1)
				(type default)
			)
			(layer "B.Fab")
		)
		(fp_line
			(start -0.120396 0.2794)
			(end 0.12065 0.2794)
			(stroke
				(width 0.1)
				(type default)
			)
			(layer "B.Fab")
		)
		(fp_line
			(start -0.120396 0.3048)
			(end -0.120396 0.2794)
			(stroke
				(width 0.1)
				(type default)
			)
			(layer "B.Fab")
		)
		(fp_line
			(start 0.12065 -0.305054)
			(end 0.12065 -0.2794)
			(stroke
				(width 0.1)
				(type default)
			)
			(layer "B.Fab")
		)
		(fp_line
			(start 0.12065 -0.2794)
			(end -0.12065 -0.2794)
			(stroke
				(width 0.1)
				(type default)
			)
			(layer "B.Fab")
		)
		(fp_line
			(start 0.12065 0.2794)
			(end 0.12065 0.3048)
			(stroke
				(width 0.1)
				(type default)
			)
			(layer "B.Fab")
		)
		(fp_line
			(start 0.12065 0.3048)
			(end 0.67945 0.3048)
			(stroke
				(width 0.1)
				(type default)
			)
			(layer "B.Fab")
		)
		(fp_line
			(start 0.67945 -0.305054)
			(end 0.12065 -0.305054)
			(stroke
				(width 0.1)
				(type default)
			)
			(layer "B.Fab")
		)
		(fp_line
			(start 0.67945 0.3048)
			(end 0.67945 -0.305054)
			(stroke
				(width 0.1)
				(type default)
			)
			(layer "B.Fab")
		)
		(pad "1" smd circle
			(at 0.40005 0 180)
			(size 0 0)
			(layers "B.Cu" "B.Mask" "B.Paste")
			(net "P3V3_AUX")
		)
		(pad "2" smd circle
			(at -0.40005 0 180)
			(size 0 0)
			(layers "B.Cu" "B.Mask" "B.Paste")
			(net "GND")
		)
	)
	(footprint ""
		(layer "B.Cu")
		(at 121.960386 -268.418564)
		(property "Reference" "C2370"
			(at 0 0 0)
			(layer "B.SilkS")
			(hide yes)
			(effects
				(font
					(size 1.27 1.27)
				)
				(justify mirror)
			)
		)
		(property "Value" ""
			(at 0 0 0)
			(layer "B.Fab")
			(effects
				(font
					(size 1.27 1.27)
				)
				(justify mirror)
			)
		)
		(duplicate_pad_numbers_are_jumpers no)
		(fp_line
			(start -0.7874 -0.4064)
			(end -0.7874 0.4064)
			(stroke
				(width 0.1524)
				(type default)
			)
			(layer "B.SilkS")
		)
		(fp_line
			(start -0.7874 0.4064)
			(end 0.7874 0.4064)
			(stroke
				(width 0.1524)
				(type default)
			)
			(layer "B.SilkS")
		)
		(fp_line
			(start 0.7874 -0.4064)
			(end -0.7874 -0.4064)
			(stroke
				(width 0.1524)
				(type default)
			)
			(layer "B.SilkS")
		)
		(fp_line
			(start 0.7874 0.4064)
			(end 0.7874 -0.4064)
			(stroke
				(width 0.1524)
				(type default)
			)
			(layer "B.SilkS")
		)
		(fp_line
			(start -0.67945 -0.3048)
			(end -0.67945 0.3048)
			(stroke
				(width 0.1)
				(type default)
			)
			(layer "B.Fab")
		)
		(fp_line
			(start -0.67945 0.3048)
			(end -0.120396 0.3048)
			(stroke
				(width 0.1)
				(type default)
			)
			(layer "B.Fab")
		)
		(fp_line
			(start -0.12065 -0.3048)
			(end -0.67945 -0.3048)
			(stroke
				(width 0.1)
				(type default)
			)
			(layer "B.Fab")
		)
		(fp_line
			(start -0.12065 -0.2794)
			(end -0.12065 -0.3048)
			(stroke
				(width 0.1)
				(type default)
			)
			(layer "B.Fab")
		)
		(fp_line
			(start -0.120396 0.2794)
			(end 0.12065 0.2794)
			(stroke
				(width 0.1)
				(type default)
			)
			(layer "B.Fab")
		)
		(fp_line
			(start -0.120396 0.3048)
			(end -0.120396 0.2794)
			(stroke
				(width 0.1)
				(type default)
			)
			(layer "B.Fab")
		)
		(fp_line
			(start 0.12065 -0.305054)
			(end 0.12065 -0.2794)
			(stroke
				(width 0.1)
				(type default)
			)
			(layer "B.Fab")
		)
		(fp_line
			(start 0.12065 -0.2794)
			(end -0.12065 -0.2794)
			(stroke
				(width 0.1)
				(type default)
			)
			(layer "B.Fab")
		)
		(fp_line
			(start 0.12065 0.2794)
			(end 0.12065 0.3048)
			(stroke
				(width 0.1)
				(type default)
			)
			(layer "B.Fab")
		)
		(fp_line
			(start 0.12065 0.3048)
			(end 0.67945 0.3048)
			(stroke
				(width 0.1)
				(type default)
			)
			(layer "B.Fab")
		)
		(fp_line
			(start 0.67945 -0.305054)
			(end 0.12065 -0.305054)
			(stroke
				(width 0.1)
				(type default)
			)
			(layer "B.Fab")
		)
		(fp_line
			(start 0.67945 0.3048)
			(end 0.67945 -0.305054)
			(stroke
				(width 0.1)
				(type default)
			)
			(layer "B.Fab")
		)
		(pad "1" smd circle
			(at 0.40005 0 180)
			(size 0 0)
			(layers "B.Cu" "B.Mask" "B.Paste")
			(net "PVDDCR_CPU1_P1")
		)
		(pad "2" smd circle
			(at -0.40005 0 180)
			(size 0 0)
			(layers "B.Cu" "B.Mask" "B.Paste")
			(net "GND")
		)
	)
	(footprint ""
		(layer "B.Cu")
		(at 412.256986 -151.346916 90)
		(property "Reference" "PC1856"
			(at 0 0 90)
			(layer "B.SilkS")
			(hide yes)
			(effects
				(font
					(size 1.27 1.27)
				)
				(justify mirror)
			)
		)
		(property "Value" ""
			(at 0 0 90)
			(layer "B.Fab")
			(effects
				(font
					(size 1.27 1.27)
				)
				(justify mirror)
			)
		)
		(duplicate_pad_numbers_are_jumpers no)
		(fp_line
			(start 1.524 -0.762)
			(end -1.524 -0.762)
			(stroke
				(width 0.1524)
				(type default)
			)
			(layer "B.SilkS")
		)
		(fp_line
			(start -1.524 -0.762)
			(end -1.524 0.762)
			(stroke
				(width 0.1524)
				(type default)
			)
			(layer "B.SilkS")
		)
		(fp_line
			(start 1.524 0.762)
			(end 1.524 -0.762)
			(stroke
				(width 0.1524)
				(type default)
			)
			(layer "B.SilkS")
		)
		(fp_line
			(start -1.524 0.762)
			(end 1.524 0.762)
			(stroke
				(width 0.1524)
				(type default)
			)
			(layer "B.SilkS")
		)
		(fp_line
			(start 1.1049 -0.724916)
			(end 1.1049 0.724916)
			(stroke
				(width 0.1)
				(type default)
			)
			(layer "B.Fab")
		)
		(fp_line
			(start -1.1049 -0.724916)
			(end 1.1049 -0.724916)
			(stroke
				(width 0.1)
				(type default)
			)
			(layer "B.Fab")
		)
		(fp_line
			(start 1.1049 0.724916)
			(end -1.1049 0.724916)
			(stroke
				(width 0.1)
				(type default)
			)
			(layer "B.Fab")
		)
		(fp_line
			(start -1.1049 0.724916)
			(end -1.1049 -0.724916)
			(stroke
				(width 0.1)
				(type default)
			)
			(layer "B.Fab")
		)
		(pad "1" smd rect
			(at 0.889 0 90)
			(size 1.016 1.27)
			(layers "B.Cu" "B.Mask" "B.Paste")
			(net "P5V_AUX")
		)
		(pad "2" smd rect
			(at -0.889 0 90)
			(size 1.016 1.27)
			(layers "B.Cu" "B.Mask" "B.Paste")
			(net "GND")
		)
	)
	(footprint ""
		(layer "B.Cu")
		(at 117.896386 -249.368564)
		(property "Reference" "C2297"
			(at 0 0 0)
			(layer "B.SilkS")
			(hide yes)
			(effects
				(font
					(size 1.27 1.27)
				)
				(justify mirror)
			)
		)
		(property "Value" ""
			(at 0 0 0)
			(layer "B.Fab")
			(effects
				(font
					(size 1.27 1.27)
				)
				(justify mirror)
			)
		)
		(duplicate_pad_numbers_are_jumpers no)
		(fp_line
			(start -0.7874 -0.4064)
			(end -0.7874 0.4064)
			(stroke
				(width 0.1524)
				(type default)
			)
			(layer "B.SilkS")
		)
		(fp_line
			(start -0.7874 0.4064)
			(end 0.7874 0.4064)
			(stroke
				(width 0.1524)
				(type default)
			)
			(layer "B.SilkS")
		)
		(fp_line
			(start 0.7874 -0.4064)
			(end -0.7874 -0.4064)
			(stroke
				(width 0.1524)
				(type default)
			)
			(layer "B.SilkS")
		)
		(fp_line
			(start 0.7874 0.4064)
			(end 0.7874 -0.4064)
			(stroke
				(width 0.1524)
				(type default)
			)
			(layer "B.SilkS")
		)
		(fp_line
			(start -0.67945 -0.3048)
			(end -0.67945 0.3048)
			(stroke
				(width 0.1)
				(type default)
			)
			(layer "B.Fab")
		)
		(fp_line
			(start -0.67945 0.3048)
			(end -0.120396 0.3048)
			(stroke
				(width 0.1)
				(type default)
			)
			(layer "B.Fab")
		)
		(fp_line
			(start -0.12065 -0.3048)
			(end -0.67945 -0.3048)
			(stroke
				(width 0.1)
				(type default)
			)
			(layer "B.Fab")
		)
		(fp_line
			(start -0.12065 -0.2794)
			(end -0.12065 -0.3048)
			(stroke
				(width 0.1)
				(type default)
			)
			(layer "B.Fab")
		)
		(fp_line
			(start -0.120396 0.2794)
			(end 0.12065 0.2794)
			(stroke
				(width 0.1)
				(type default)
			)
			(layer "B.Fab")
		)
		(fp_line
			(start -0.120396 0.3048)
			(end -0.120396 0.2794)
			(stroke
				(width 0.1)
				(type default)
			)
			(layer "B.Fab")
		)
		(fp_line
			(start 0.12065 -0.305054)
			(end 0.12065 -0.2794)
			(stroke
				(width 0.1)
				(type default)
			)
			(layer "B.Fab")
		)
		(fp_line
			(start 0.12065 -0.2794)
			(end -0.12065 -0.2794)
			(stroke
				(width 0.1)
				(type default)
			)
			(layer "B.Fab")
		)
		(fp_line
			(start 0.12065 0.2794)
			(end 0.12065 0.3048)
			(stroke
				(width 0.1)
				(type default)
			)
			(layer "B.Fab")
		)
		(fp_line
			(start 0.12065 0.3048)
			(end 0.67945 0.3048)
			(stroke
				(width 0.1)
				(type default)
			)
			(layer "B.Fab")
		)
		(fp_line
			(start 0.67945 -0.305054)
			(end 0.12065 -0.305054)
			(stroke
				(width 0.1)
				(type default)
			)
			(layer "B.Fab")
		)
		(fp_line
			(start 0.67945 0.3048)
			(end 0.67945 -0.305054)
			(stroke
				(width 0.1)
				(type default)
			)
			(layer "B.Fab")
		)
		(pad "1" smd circle
			(at 0.40005 0 180)
			(size 0 0)
			(layers "B.Cu" "B.Mask" "B.Paste")
			(net "PVDDCR_CPU0_P1")
		)
		(pad "2" smd circle
			(at -0.40005 0 180)
			(size 0 0)
			(layers "B.Cu" "B.Mask" "B.Paste")
			(net "GND")
		)
	)
	(footprint ""
		(layer "B.Cu")
		(at 312.341006 -416.899344 90)
		(property "Reference" "C6537"
			(at 0 0 90)
			(layer "B.SilkS")
			(hide yes)
			(effects
				(font
					(size 1.27 1.27)
				)
				(justify mirror)
			)
		)
		(property "Value" ""
			(at 0 0 90)
			(layer "B.Fab")
			(effects
				(font
					(size 1.27 1.27)
				)
				(justify mirror)
			)
		)
		(duplicate_pad_numbers_are_jumpers no)
		(fp_line
			(start 0.299974 -0.150114)
			(end -0.299974 -0.150114)
			(stroke
				(width 0.1)
				(type default)
			)
			(layer "B.Fab")
		)
		(fp_line
			(start -0.299974 -0.150114)
			(end -0.299974 0.150114)
			(stroke
				(width 0.1)
				(type default)
			)
			(layer "B.Fab")
		)
		(fp_line
			(start 0.299974 0.150114)
			(end 0.299974 -0.150114)
			(stroke
				(width 0.1)
				(type default)
			)
			(layer "B.Fab")
		)
		(fp_line
			(start -0.299974 0.150114)
			(end 0.299974 0.150114)
			(stroke
				(width 0.1)
				(type default)
			)
			(layer "B.Fab")
		)
		(pad "1" smd rect
			(at 0.2667 0 270)
			(size 0.3048 0.381)
			(layers "B.Cu" "B.Mask" "B.Paste")
			(net "P5E_CPU0_P1_TX_BUF_C_DP<2>")
		)
		(pad "2" smd rect
			(at -0.2667 0 270)
			(size 0.3048 0.381)
			(layers "B.Cu" "B.Mask" "B.Paste")
			(net "P5E_CPU0_P1_TX_BUF_DP<2>")
		)
	)
	(footprint ""
		(layer "B.Cu")
		(at 419.062916 -172.407072 90)
		(property "Reference" "PC615_3"
			(at 0 0 90)
			(layer "B.SilkS")
			(hide yes)
			(effects
				(font
					(size 1.27 1.27)
				)
				(justify mirror)
			)
		)
		(property "Value" ""
			(at 0 0 90)
			(layer "B.Fab")
			(effects
				(font
					(size 1.27 1.27)
				)
				(justify mirror)
			)
		)
		(duplicate_pad_numbers_are_jumpers no)
		(fp_line
			(start 1.524 -0.762)
			(end -1.524 -0.762)
			(stroke
				(width 0.1524)
				(type default)
			)
			(layer "B.SilkS")
		)
		(fp_line
			(start -1.524 -0.762)
			(end -1.524 0.762)
			(stroke
				(width 0.1524)
				(type default)
			)
			(layer "B.SilkS")
		)
		(fp_line
			(start 1.524 0.762)
			(end 1.524 -0.762)
			(stroke
				(width 0.1524)
				(type default)
			)
			(layer "B.SilkS")
		)
		(fp_line
			(start -1.524 0.762)
			(end 1.524 0.762)
			(stroke
				(width 0.1524)
				(type default)
			)
			(layer "B.SilkS")
		)
		(fp_line
			(start 1.1049 -0.724916)
			(end 1.1049 0.724916)
			(stroke
				(width 0.1)
				(type default)
			)
			(layer "B.Fab")
		)
		(fp_line
			(start -1.1049 -0.724916)
			(end 1.1049 -0.724916)
			(stroke
				(width 0.1)
				(type default)
			)
			(layer "B.Fab")
		)
		(fp_line
			(start 1.1049 0.724916)
			(end -1.1049 0.724916)
			(stroke
				(width 0.1)
				(type default)
			)
			(layer "B.Fab")
		)
		(fp_line
			(start -1.1049 0.724916)
			(end -1.1049 -0.724916)
			(stroke
				(width 0.1)
				(type default)
			)
			(layer "B.Fab")
		)
		(pad "1" smd rect
			(at 0.889 0 90)
			(size 1.016 1.27)
			(layers "B.Cu" "B.Mask" "B.Paste")
			(net "PVDDCR_SOC_P0")
		)
		(pad "2" smd rect
			(at -0.889 0 90)
			(size 1.016 1.27)
			(layers "B.Cu" "B.Mask" "B.Paste")
			(net "GND")
		)
	)
)
